# SCM (Grand Teton) — schematic netlist excerpt (pin names and nets, part order shuffled) for the footprints in the layout excerpt that follows; sources: Cadence DE-HDL packaged netlist, KiCad conversion of 12092022_DA0F0TMDCD0_F0T_Management_Board_D_brd_V3_OCP.brd

J26  PICOPROBE_BXA  DELTA-L 4.0 EMPTY  pkg TRIANG_LAUNCH_3PXB  page 58
  \1_p\  = 85_10INCH_IN4_DN
  \2_n\  = 85_10INCH_IN4_DP
  \3_g\  = GND_P1

(kicad_pcb
	(version 20260206)
	(generator "pcbnew")
	(generator_version "10.0")
	(general
		(thickness 1.6)
		(legacy_teardrops no)
	)
	(paper "A4")
	(title_block
		(title "12092022_DA0F0TMDCD0_F0T_Management_Board_D_brd_V3_OCP.brd")
		(comment 1 "Grand Teton / footprints 56-56 of 1440")
	)
	(layers
		(0 "F.Cu" signal "TOP")
		(4 "In1.Cu" signal "GND")
		(6 "In2.Cu" signal "IN1")
		(8 "In3.Cu" signal "GND1")
		(10 "In4.Cu" signal "IN2")
		(12 "In5.Cu" signal "VCC")
		(14 "In6.Cu" signal "VCC1")
		(16 "In7.Cu" signal "IN3")
		(18 "In8.Cu" signal "GND2")
		(20 "In9.Cu" signal "IN4")
		(22 "In10.Cu" signal "GND3")
		(2 "B.Cu" signal "BOTTOM")
		(9 "F.Adhes" user "F.Adhesive")
		(11 "B.Adhes" user "B.Adhesive")
		(13 "F.Paste" user "Package Geometry/Pastemask Top")
		(15 "B.Paste" user "Package Geometry/Pastemask Bottom")
		(5 "F.SilkS" user "Ref Des/Silkscreen Top")
		(7 "B.SilkS" user "Ref Des/Silkscreen Bottom")
		(1 "F.Mask" user "Board Geometry/Soldermask Top")
		(3 "B.Mask" user "Board Geometry/Soldermask Bottom")
		(17 "Dwgs.User" user "User.Drawings")
		(19 "Cmts.User" user "User.Comments")
		(21 "Eco1.User" user "User.Eco1")
		(23 "Eco2.User" user "User.Eco2")
		(25 "Edge.Cuts" user "Board Geometry/Outline")
		(27 "Margin" user)
		(31 "F.CrtYd" user "Package Geometry/Place Bound Top")
		(29 "B.CrtYd" user "Package Geometry/Place Bound Bottom")
		(35 "F.Fab" user "Ref Des/Assembly Top")
		(33 "B.Fab" user "Ref Des/Assembly Bottom")
	)
	(footprint ""
		(layer "F.Cu")
		(at 95.926656 -98.400362 -90)
		(property "Reference" "J26"
			(at -3.961638 -1.509014 90)
			(unlocked yes)
			(layer "F.SilkS")
			(effects
				(font
					(size 0.7874 0.5842)
					(thickness 0.1524)
				)
				(justify left)
			)
		)
		(property "Value" ""
			(at 0 0 270)
			(layer "F.Fab")
			(effects
				(font
					(size 1.27 1.27)
				)
			)
		)
		(duplicate_pad_numbers_are_jumpers no)
		(fp_line
			(start -1.2192 2.1082)
			(end -1.2192 -2.1082)
			(stroke
				(width 0.1524)
				(type default)
			)
			(layer "F.SilkS")
		)
		(fp_line
			(start 1.2192 2.1082)
			(end -1.2192 2.1082)
			(stroke
				(width 0.1524)
				(type default)
			)
			(layer "F.SilkS")
		)
		(fp_line
			(start 1.2192 0.80137)
			(end 1.2192 2.1082)
			(stroke
				(width 0.1524)
				(type default)
			)
			(layer "F.SilkS")
		)
		(fp_line
			(start -1.2192 -2.1082)
			(end 1.2192 -2.1082)
			(stroke
				(width 0.1524)
				(type default)
			)
			(layer "F.SilkS")
		)
		(fp_line
			(start 1.2192 -2.1082)
			(end 1.2192 -0.816102)
			(stroke
				(width 0.1524)
				(type default)
			)
			(layer "F.SilkS")
		)
		(pad "" np_thru_hole circle
			(at -2.8829 -1.27 180)
			(size 1.0414 1.0414)
			(drill 1.0414)
			(layers "*.Cu" "*.Mask")
			(clearance 0.381)
			(thermal_gap 0.381)
		)
		(pad "" np_thru_hole circle
			(at -2.8829 1.27 180)
			(size 1.0414 1.0414)
			(drill 1.0414)
			(layers "*.Cu" "*.Mask")
			(clearance 0.381)
			(thermal_gap 0.381)
		)
		(pad "" np_thru_hole circle
			(at 3.4671 -1.27 180)
			(size 1.0414 1.0414)
			(drill 1.0414)
			(layers "*.Cu" "*.Mask")
			(clearance 0.381)
			(thermal_gap 0.381)
		)
		(pad "" np_thru_hole circle
			(at 3.4671 1.27 180)
			(size 1.0414 1.0414)
			(drill 1.0414)
			(layers "*.Cu" "*.Mask")
			(clearance 0.381)
			(thermal_gap 0.381)
		)
		(pad "1" smd rect
			(at 0.8255 -0.249936 180)
			(size 0.3048 0.508)
			(layers "F.Cu" "F.Mask" "F.Paste")
			(net "85_10INCH_IN4_DN")
		)
		(pad "2" smd rect
			(at 0.8255 0.249936 180)
			(size 0.3048 0.508)
			(layers "F.Cu" "F.Mask" "F.Paste")
			(net "85_10INCH_IN4_DP")
		)
		(pad "3" smd circle
			(at 0 0 270)
			(size 0 0)
			(layers "F.Cu" "F.Mask" "F.Paste")
			(net "GND_P1")
		)
		(zone
			(layer "F.Cu")
			(hatch none 0.5)
			(connect_pads
				(clearance 0)
			)
			(min_thickness 0.25)
			(keepout
				(tracks not_allowed)
				(vias allowed)
				(pads allowed)
				(copperpour not_allowed)
				(footprints allowed)
			)
			(placement
				(enabled no)
				(sheetname "")
			)
			(fill
				(thermal_gap 0.5)
				(thermal_bridge_width 0.5)
				(island_removal_mode 0)
			)
			(polygon
				(pts
					(xy 96.475296 -97.282762) (xy 96.379792 -97.282762) (xy 96.379792 -97.879662) (xy 95.973392 -97.879662)
					(xy 95.973392 -97.282762) (xy 95.87992 -97.282762) (xy 95.87992 -97.879662) (xy 95.47352 -97.879662)
					(xy 95.47352 -97.282762) (xy 95.378016 -97.282762) (xy 95.378016 -97.981262) (xy 96.475296 -97.981262)
				)
			)
		)
		(zone
			(layers "F.Cu" "B.Cu" "In1.Cu" "In2.Cu" "In3.Cu" "In4.Cu" "In5.Cu" "In6.Cu"
				"In7.Cu" "In8.Cu" "In9.Cu" "In10.Cu"
			)
			(hatch none 0.5)
			(connect_pads
				(clearance 0)
			)
			(min_thickness 0.25)
			(keepout
				(tracks not_allowed)
				(vias allowed)
				(pads allowed)
				(copperpour not_allowed)
				(footprints allowed)
			)
			(placement
				(enabled no)
				(sheetname "")
			)
			(fill
				(thermal_gap 0.5)
				(thermal_bridge_width 0.5)
				(island_removal_mode 0)
			)
			(polygon
				(pts
					(arc
						(start 95.583756 -101.283262)
						(mid 93.729556 -101.283262)
						(end 95.583756 -101.283262)
					)
				)
			)
		)
		(zone
			(layers "F.Cu" "B.Cu" "In1.Cu" "In2.Cu" "In3.Cu" "In4.Cu" "In5.Cu" "In6.Cu"
				"In7.Cu" "In8.Cu" "In9.Cu" "In10.Cu"
			)
			(hatch none 0.5)
			(connect_pads
				(clearance 0)
			)
			(min_thickness 0.25)
			(keepout
				(tracks not_allowed)
				(vias allowed)
				(pads allowed)
				(copperpour not_allowed)
				(footprints allowed)
			)
			(placement
				(enabled no)
				(sheetname "")
			)
			(fill
				(thermal_gap 0.5)
				(thermal_bridge_width 0.5)
				(island_removal_mode 0)
			)
			(polygon
				(pts
					(arc
						(start 95.583756 -94.933262)
						(mid 93.729556 -94.933262)
						(end 95.583756 -94.933262)
					)
				)
			)
		)
		(zone
			(layers "F.Cu" "B.Cu" "In1.Cu" "In2.Cu" "In3.Cu" "In4.Cu" "In5.Cu" "In6.Cu"
				"In7.Cu" "In8.Cu" "In9.Cu" "In10.Cu"
			)
			(hatch none 0.5)
			(connect_pads
				(clearance 0)
			)
			(min_thickness 0.25)
			(keepout
				(tracks not_allowed)
				(vias allowed)
				(pads allowed)
				(copperpour not_allowed)
				(footprints allowed)
			)
			(placement
				(enabled no)
				(sheetname "")
			)
			(fill
				(thermal_gap 0.5)
				(thermal_bridge_width 0.5)
				(island_removal_mode 0)
			)
			(polygon
				(pts
					(arc
						(start 98.123756 -101.283262)
						(mid 96.269556 -101.283262)
						(end 98.123756 -101.283262)
					)
				)
			)
		)
		(zone
			(layers "F.Cu" "B.Cu" "In1.Cu" "In2.Cu" "In3.Cu" "In4.Cu" "In5.Cu" "In6.Cu"
				"In7.Cu" "In8.Cu" "In9.Cu" "In10.Cu"
			)
			(hatch none 0.5)
			(connect_pads
				(clearance 0)
			)
			(min_thickness 0.25)
			(keepout
				(tracks not_allowed)
				(vias allowed)
				(pads allowed)
				(copperpour not_allowed)
				(footprints allowed)
			)
			(placement
				(enabled no)
				(sheetname "")
			)
			(fill
				(thermal_gap 0.5)
				(thermal_bridge_width 0.5)
				(island_removal_mode 0)
			)
			(polygon
				(pts
					(arc
						(start 98.123756 -94.933262)
						(mid 96.269556 -94.933262)
						(end 98.123756 -94.933262)
					)
				)
			)
		)
	)
)
